(kicad_pcb
	(version 20260206)
	(generator "pcbnew")
	(generator_version "10.0")
	(general
		(thickness 1.6)
		(legacy_teardrops no)
	)
	(paper "A4")
	(title_block
		(title "baseboard — 13948-1b.1110WZS1818.brd")
		(comment 1 "Honey Badger (Wiwynn) / footprints 948-954 of 2523")
	)
	(layers
		(0 "F.Cu" signal "TOP")
		(4 "In1.Cu" signal "L2GND")
		(6 "In2.Cu" signal "L3")
		(8 "In3.Cu" signal "L4VCC")
		(10 "In4.Cu" signal "L5VCC")
		(12 "In5.Cu" signal "L6")
		(14 "In6.Cu" signal "L7GND")
		(2 "B.Cu" signal "BOTTOM")
		(9 "F.Adhes" user "F.Adhesive")
		(11 "B.Adhes" user "B.Adhesive")
		(13 "F.Paste" user "Package Geometry/Pastemask Top")
		(15 "B.Paste" user "Package Geometry/Pastemask Bottom")
		(5 "F.SilkS" user "Ref Des/Silkscreen Top")
		(7 "B.SilkS" user "Ref Des/Silkscreen Bottom")
		(1 "F.Mask" user "Board Geometry/Soldermask Top")
		(3 "B.Mask" user "Board Geometry/Soldermask Bottom")
		(17 "Dwgs.User" user "User.Drawings")
		(19 "Cmts.User" user "User.Comments")
		(21 "Eco1.User" user "User.Eco1")
		(23 "Eco2.User" user "User.Eco2")
		(25 "Edge.Cuts" user "Board Geometry/Outline")
		(27 "Margin" user)
		(31 "F.CrtYd" user "Package Geometry/Place Bound Top")
		(29 "B.CrtYd" user "Package Geometry/Place Bound Bottom")
		(35 "F.Fab" user "Ref Des/Assembly Top")
		(33 "B.Fab" user "Ref Des/Assembly Bottom")
	)
	(footprint ""
		(layer "F.Cu")
		(at 102.616 -224.79 90)
		(property "Reference" "R645"
			(at 0 0 90)
			(layer "F.SilkS")
			(hide yes)
			(effects
				(font
					(size 1.27 1.27)
				)
			)
		)
		(property "Value" "4K7R2F-GP"
			(at 0.064008 -3.993896 90)
			(unlocked yes)
			(layer "F.Fab")
			(hide yes)
			(effects
				(font
					(size 1.016 1.016)
					(thickness 0.1524)
				)
			)
		)
		(property "Device Type" "R402H16"
			(at 0.064008 -5.517896 90)
			(unlocked yes)
			(layer "F.Fab")
			(hide yes)
			(effects
				(font
					(size 1.016 1.016)
					(thickness 0.1524)
				)
			)
		)
		(duplicate_pad_numbers_are_jumpers no)
		(fp_line
			(start 0.508 -0.9398)
			(end -0.508 -0.9398)
			(stroke
				(width 0.1524)
				(type default)
			)
			(layer "F.SilkS")
		)
		(fp_line
			(start -0.508 -0.9398)
			(end -0.508 0.9398)
			(stroke
				(width 0.1524)
				(type default)
			)
			(layer "F.SilkS")
		)
		(fp_rect
			(start -0.508 0.9398)
			(end 0.508 -0.9398)
			(stroke
				(width 0)
				(type default)
			)
			(fill no)
			(layer "F.CrtYd")
		)
		(fp_rect
			(start -0.508 0.9398)
			(end 0.508 -0.9398)
			(stroke
				(width 0)
				(type default)
			)
			(fill no)
			(layer "F.Fab")
		)
		(pad "1" smd custom
			(at 0 -0.4445 90)
			(size 0.1397 0.1397)
			(layers "F.Cu" "F.Mask" "F.Paste")
			(net "IO_EXP_HDD_FAULT_A2")
			(options
				(clearance outline)
				(anchor circle)
			)
			(primitives
				(gr_poly
					(pts
						(arc
							(start -0.1778 -0.2794)
							(mid -0.249642 -0.249642)
							(end -0.2794 -0.1778)
						)
						(arc
							(start -0.2794 0.1778)
							(mid -0.249642 0.249642)
							(end -0.1778 0.2794)
						)
						(arc
							(start 0.1778 0.2794)
							(mid 0.249642 0.249642)
							(end 0.2794 0.1778)
						)
						(arc
							(start 0.2794 -0.1778)
							(mid 0.249642 -0.249642)
							(end 0.1778 -0.2794)
						)
					)
					(width 0)
					(fill yes)
				)
			)
		)
		(pad "2" smd custom
			(at 0 0.4445 90)
			(size 0.1397 0.1397)
			(layers "F.Cu" "F.Mask" "F.Paste")
			(net "GND")
			(options
				(clearance outline)
				(anchor circle)
			)
			(primitives
				(gr_poly
					(pts
						(arc
							(start -0.1778 -0.2794)
							(mid -0.249642 -0.249642)
							(end -0.2794 -0.1778)
						)
						(arc
							(start -0.2794 0.1778)
							(mid -0.249642 0.249642)
							(end -0.1778 0.2794)
						)
						(arc
							(start 0.1778 0.2794)
							(mid 0.249642 0.249642)
							(end 0.2794 0.1778)
						)
						(arc
							(start 0.2794 -0.1778)
							(mid 0.249642 -0.249642)
							(end 0.1778 -0.2794)
						)
					)
					(width 0)
					(fill yes)
				)
			)
		)
	)
	(footprint ""
		(layer "F.Cu")
		(at 182.888128 -14.151864 180)
		(property "Reference" "R188"
			(at 0 0 180)
			(layer "F.SilkS")
			(hide yes)
			(effects
				(font
					(size 1.27 1.27)
				)
			)
		)
		(property "Value" "4K7R2F-GP"
			(at 0.064008 -3.993896 180)
			(unlocked yes)
			(layer "F.Fab")
			(hide yes)
			(effects
				(font
					(size 1.016 1.016)
					(thickness 0.1524)
				)
			)
		)
		(property "Device Type" "R402H16"
			(at 0.064008 -5.517896 180)
			(unlocked yes)
			(layer "F.Fab")
			(hide yes)
			(effects
				(font
					(size 1.016 1.016)
					(thickness 0.1524)
				)
			)
		)
		(duplicate_pad_numbers_are_jumpers no)
		(fp_line
			(start 0.508 -0.9398)
			(end -0.508 -0.9398)
			(stroke
				(width 0.1524)
				(type default)
			)
			(layer "F.SilkS")
		)
		(fp_line
			(start -0.508 -0.9398)
			(end -0.508 0.9398)
			(stroke
				(width 0.1524)
				(type default)
			)
			(layer "F.SilkS")
		)
		(fp_rect
			(start -0.508 0.9398)
			(end 0.508 -0.9398)
			(stroke
				(width 0)
				(type default)
			)
			(fill no)
			(layer "F.CrtYd")
		)
		(fp_rect
			(start -0.508 0.9398)
			(end 0.508 -0.9398)
			(stroke
				(width 0)
				(type default)
			)
			(fill no)
			(layer "F.Fab")
		)
		(pad "1" smd custom
			(at 0 -0.4445 180)
			(size 0.1397 0.1397)
			(layers "F.Cu" "F.Mask" "F.Paste")
			(net "P3V3_STBY")
			(options
				(clearance outline)
				(anchor circle)
			)
			(primitives
				(gr_poly
					(pts
						(arc
							(start -0.1778 -0.2794)
							(mid -0.249642 -0.249642)
							(end -0.2794 -0.1778)
						)
						(arc
							(start -0.2794 0.1778)
							(mid -0.249642 0.249642)
							(end -0.1778 0.2794)
						)
						(arc
							(start 0.1778 0.2794)
							(mid 0.249642 0.249642)
							(end 0.2794 0.1778)
						)
						(arc
							(start 0.2794 -0.1778)
							(mid 0.249642 -0.249642)
							(end 0.1778 -0.2794)
						)
					)
					(width 0)
					(fill yes)
				)
			)
		)
		(pad "2" smd custom
			(at 0 0.4445 180)
			(size 0.1397 0.1397)
			(layers "F.Cu" "F.Mask" "F.Paste")
			(net "TEMP_1_A0")
			(options
				(clearance outline)
				(anchor circle)
			)
			(primitives
				(gr_poly
					(pts
						(arc
							(start -0.1778 -0.2794)
							(mid -0.249642 -0.249642)
							(end -0.2794 -0.1778)
						)
						(arc
							(start -0.2794 0.1778)
							(mid -0.249642 0.249642)
							(end -0.1778 0.2794)
						)
						(arc
							(start 0.1778 0.2794)
							(mid 0.249642 0.249642)
							(end 0.2794 0.1778)
						)
						(arc
							(start 0.2794 -0.1778)
							(mid 0.249642 -0.249642)
							(end 0.1778 -0.2794)
						)
					)
					(width 0)
					(fill yes)
				)
			)
		)
	)
	(footprint ""
		(layer "F.Cu")
		(at 346.231718 -143.233648)
		(property "Reference" "R700"
			(at 0 0 0)
			(layer "F.SilkS")
			(hide yes)
			(effects
				(font
					(size 1.27 1.27)
				)
			)
		)
		(property "Value" "12KR2J-L-GP"
			(at 0.064008 -3.993896 0)
			(unlocked yes)
			(layer "F.Fab")
			(hide yes)
			(effects
				(font
					(size 1.016 1.016)
					(thickness 0.1524)
				)
			)
		)
		(property "Device Type" "R402H16"
			(at 0.064008 -5.517896 0)
			(unlocked yes)
			(layer "F.Fab")
			(hide yes)
			(effects
				(font
					(size 1.016 1.016)
					(thickness 0.1524)
				)
			)
		)
		(duplicate_pad_numbers_are_jumpers no)
		(fp_line
			(start -0.508 -0.9398)
			(end -0.508 0.9398)
			(stroke
				(width 0.1524)
				(type default)
			)
			(layer "F.SilkS")
		)
		(fp_line
			(start 0.508 -0.9398)
			(end -0.508 -0.9398)
			(stroke
				(width 0.1524)
				(type default)
			)
			(layer "F.SilkS")
		)
		(fp_rect
			(start -0.508 0.9398)
			(end 0.508 -0.9398)
			(stroke
				(width 0)
				(type default)
			)
			(fill no)
			(layer "F.CrtYd")
		)
		(fp_rect
			(start -0.508 0.9398)
			(end 0.508 -0.9398)
			(stroke
				(width 0)
				(type default)
			)
			(fill no)
			(layer "F.Fab")
		)
		(pad "1" smd custom
			(at 0 -0.4445)
			(size 0.1397 0.1397)
			(layers "F.Cu" "F.Mask" "F.Paste")
			(net "RBIAS")
			(options
				(clearance outline)
				(anchor circle)
			)
			(primitives
				(gr_poly
					(pts
						(arc
							(start -0.1778 -0.2794)
							(mid -0.249642 -0.249642)
							(end -0.2794 -0.1778)
						)
						(arc
							(start -0.2794 0.1778)
							(mid -0.249642 0.249642)
							(end -0.1778 0.2794)
						)
						(arc
							(start 0.1778 0.2794)
							(mid 0.249642 0.249642)
							(end 0.2794 0.1778)
						)
						(arc
							(start 0.2794 -0.1778)
							(mid 0.249642 -0.249642)
							(end 0.1778 -0.2794)
						)
					)
					(width 0)
					(fill yes)
				)
			)
		)
		(pad "2" smd custom
			(at 0 0.4445)
			(size 0.1397 0.1397)
			(layers "F.Cu" "F.Mask" "F.Paste")
			(net "GND")
			(options
				(clearance outline)
				(anchor circle)
			)
			(primitives
				(gr_poly
					(pts
						(arc
							(start -0.1778 -0.2794)
							(mid -0.249642 -0.249642)
							(end -0.2794 -0.1778)
						)
						(arc
							(start -0.2794 0.1778)
							(mid -0.249642 0.249642)
							(end -0.1778 0.2794)
						)
						(arc
							(start 0.1778 0.2794)
							(mid 0.249642 0.249642)
							(end 0.2794 0.1778)
						)
						(arc
							(start 0.2794 -0.1778)
							(mid 0.249642 -0.249642)
							(end 0.1778 -0.2794)
						)
					)
					(width 0)
					(fill yes)
				)
			)
		)
	)
	(footprint ""
		(layer "F.Cu")
		(at 290.313872 -64.207136 90)
		(property "Reference" "PC137"
			(at 0 0 90)
			(layer "F.SilkS")
			(hide yes)
			(effects
				(font
					(size 1.27 1.27)
				)
			)
		)
		(property "Value" "SCD47U25V3KX-3-GP"
			(at 0 -2.8194 90)
			(unlocked yes)
			(layer "F.Fab")
			(hide yes)
			(effects
				(font
					(size 1.016 1.016)
					(thickness 0.1524)
				)
			)
		)
		(property "Device Type" "C603H36"
			(at 0 -4.3434 90)
			(unlocked yes)
			(layer "F.Fab")
			(hide yes)
			(effects
				(font
					(size 1.016 1.016)
					(thickness 0.1524)
				)
			)
		)
		(duplicate_pad_numbers_are_jumpers no)
		(fp_line
			(start 0.508 0)
			(end -0.508 0)
			(stroke
				(width 0.2032)
				(type default)
			)
			(layer "F.SilkS")
		)
		(fp_rect
			(start -0.5842 1.3335)
			(end 0.5842 -1.3335)
			(stroke
				(width 0)
				(type default)
			)
			(fill no)
			(layer "F.CrtYd")
		)
		(fp_rect
			(start -0.5842 1.3335)
			(end 0.5842 -1.3335)
			(stroke
				(width 0)
				(type default)
			)
			(fill no)
			(layer "F.Fab")
		)
		(pad "1" smd custom
			(at 0 -0.762 90)
			(size 0.2159 0.2159)
			(layers "F.Cu" "F.Mask" "F.Paste")
			(net "P3V3_EN_LV")
			(options
				(clearance outline)
				(anchor circle)
			)
			(primitives
				(gr_poly
					(pts
						(arc
							(start -0.3302 -0.4318)
							(mid -0.402042 -0.402042)
							(end -0.4318 -0.3302)
						)
						(arc
							(start -0.4318 0.3302)
							(mid -0.402042 0.402042)
							(end -0.3302 0.4318)
						)
						(arc
							(start 0.3302 0.4318)
							(mid 0.402042 0.402042)
							(end 0.4318 0.3302)
						)
						(arc
							(start 0.4318 -0.3302)
							(mid 0.402042 -0.402042)
							(end 0.3302 -0.4318)
						)
					)
					(width 0)
					(fill yes)
				)
			)
		)
		(pad "2" smd custom
			(at 0 0.762 90)
			(size 0.2159 0.2159)
			(layers "F.Cu" "F.Mask" "F.Paste")
			(net "P3V3")
			(options
				(clearance outline)
				(anchor circle)
			)
			(primitives
				(gr_poly
					(pts
						(arc
							(start -0.3302 -0.4318)
							(mid -0.402042 -0.402042)
							(end -0.4318 -0.3302)
						)
						(arc
							(start -0.4318 0.3302)
							(mid -0.402042 0.402042)
							(end -0.3302 0.4318)
						)
						(arc
							(start 0.3302 0.4318)
							(mid 0.402042 0.402042)
							(end 0.4318 0.3302)
						)
						(arc
							(start 0.4318 -0.3302)
							(mid 0.402042 -0.402042)
							(end 0.3302 -0.4318)
						)
					)
					(width 0)
					(fill yes)
				)
			)
		)
	)
	(footprint ""
		(layer "F.Cu")
		(at 199.009 -90.297 -90)
		(property "Reference" "PC234"
			(at 0 0 270)
			(layer "F.SilkS")
			(hide yes)
			(effects
				(font
					(size 1.27 1.27)
				)
			)
		)
		(property "Value" "SCD1U16V2KX-3GP"
			(at 1.1811 -2.7051 270)
			(unlocked yes)
			(layer "F.Fab")
			(hide yes)
			(effects
				(font
					(size 1.016 1.016)
					(thickness 0.1524)
				)
			)
		)
		(property "Device Type" "C402H22"
			(at 1.1811 -4.2291 270)
			(unlocked yes)
			(layer "F.Fab")
			(hide yes)
			(effects
				(font
					(size 1.016 1.016)
					(thickness 0.1524)
				)
			)
		)
		(duplicate_pad_numbers_are_jumpers no)
		(fp_rect
			(start -0.4318 0.9525)
			(end 0.4318 -0.9525)
			(stroke
				(width 0)
				(type default)
			)
			(fill no)
			(layer "F.CrtYd")
		)
		(fp_rect
			(start -0.4318 0.9525)
			(end 0.4318 -0.9525)
			(stroke
				(width 0)
				(type default)
			)
			(fill no)
			(layer "F.Fab")
		)
		(pad "1" smd custom
			(at 0 -0.4445 270)
			(size 0.1524 0.1524)
			(layers "F.Cu" "F.Mask" "F.Paste")
			(net "P1V5_E")
			(options
				(clearance outline)
				(anchor circle)
			)
			(primitives
				(gr_poly
					(pts
						(arc
							(start 0.3048 -0.2032)
							(mid 0.275042 -0.275042)
							(end 0.2032 -0.3048)
						)
						(arc
							(start -0.2032 -0.3048)
							(mid -0.275042 -0.275042)
							(end -0.3048 -0.2032)
						)
						(arc
							(start -0.3048 0.2032)
							(mid -0.275042 0.275042)
							(end -0.2032 0.3048)
						)
						(arc
							(start 0.2032 0.3048)
							(mid 0.275042 0.275042)
							(end 0.3048 0.2032)
						)
					)
					(width 0)
					(fill yes)
				)
			)
		)
		(pad "2" smd custom
			(at 0 0.4445 270)
			(size 0.1524 0.1524)
			(layers "F.Cu" "F.Mask" "F.Paste")
			(net "GND")
			(options
				(clearance outline)
				(anchor circle)
			)
			(primitives
				(gr_poly
					(pts
						(arc
							(start 0.3048 -0.2032)
							(mid 0.275042 -0.275042)
							(end 0.2032 -0.3048)
						)
						(arc
							(start -0.2032 -0.3048)
							(mid -0.275042 -0.275042)
							(end -0.3048 -0.2032)
						)
						(arc
							(start -0.3048 0.2032)
							(mid -0.275042 0.275042)
							(end -0.2032 0.3048)
						)
						(arc
							(start 0.2032 0.3048)
							(mid 0.275042 0.275042)
							(end 0.3048 0.2032)
						)
					)
					(width 0)
					(fill yes)
				)
			)
		)
	)
	(footprint ""
		(layer "F.Cu")
		(at 201.364596 -121.177812)
		(property "Reference" "PC239"
			(at 0 0 0)
			(layer "F.SilkS")
			(hide yes)
			(effects
				(font
					(size 1.27 1.27)
				)
			)
		)
		(property "Value" "SC1KP50V2KX-1GP"
			(at 1.1811 -2.7051 0)
			(unlocked yes)
			(layer "F.Fab")
			(hide yes)
			(effects
				(font
					(size 1.016 1.016)
					(thickness 0.1524)
				)
			)
		)
		(property "Device Type" "C402H22"
			(at 1.1811 -4.2291 0)
			(unlocked yes)
			(layer "F.Fab")
			(hide yes)
			(effects
				(font
					(size 1.016 1.016)
					(thickness 0.1524)
				)
			)
		)
		(duplicate_pad_numbers_are_jumpers no)
		(fp_rect
			(start -0.4318 0.9525)
			(end 0.4318 -0.9525)
			(stroke
				(width 0)
				(type default)
			)
			(fill no)
			(layer "F.CrtYd")
		)
		(fp_rect
			(start -0.4318 0.9525)
			(end 0.4318 -0.9525)
			(stroke
				(width 0)
				(type default)
			)
			(fill no)
			(layer "F.Fab")
		)
		(pad "1" smd custom
			(at 0 -0.4445)
			(size 0.1524 0.1524)
			(layers "F.Cu" "F.Mask" "F.Paste")
			(net "P1V5_E_VFB_R")
			(options
				(clearance outline)
				(anchor circle)
			)
			(primitives
				(gr_poly
					(pts
						(arc
							(start 0.3048 -0.2032)
							(mid 0.275042 -0.275042)
							(end 0.2032 -0.3048)
						)
						(arc
							(start -0.2032 -0.3048)
							(mid -0.275042 -0.275042)
							(end -0.3048 -0.2032)
						)
						(arc
							(start -0.3048 0.2032)
							(mid -0.275042 0.275042)
							(end -0.2032 0.3048)
						)
						(arc
							(start 0.2032 0.3048)
							(mid 0.275042 0.275042)
							(end 0.3048 0.2032)
						)
					)
					(width 0)
					(fill yes)
				)
			)
		)
		(pad "2" smd custom
			(at 0 0.4445)
			(size 0.1524 0.1524)
			(layers "F.Cu" "F.Mask" "F.Paste")
			(net "P1V5_E_VFB")
			(options
				(clearance outline)
				(anchor circle)
			)
			(primitives
				(gr_poly
					(pts
						(arc
							(start 0.3048 -0.2032)
							(mid 0.275042 -0.275042)
							(end 0.2032 -0.3048)
						)
						(arc
							(start -0.2032 -0.3048)
							(mid -0.275042 -0.275042)
							(end -0.3048 -0.2032)
						)
						(arc
							(start -0.3048 0.2032)
							(mid -0.275042 0.275042)
							(end -0.2032 0.3048)
						)
						(arc
							(start 0.2032 0.3048)
							(mid 0.275042 0.275042)
							(end 0.3048 0.2032)
						)
					)
					(width 0)
					(fill yes)
				)
			)
		)
	)
	(footprint ""
		(layer "F.Cu")
		(at 91.313 -231.775 180)
		(property "Reference" "R560"
			(at 0 0 180)
			(layer "F.SilkS")
			(hide yes)
			(effects
				(font
					(size 1.27 1.27)
				)
			)
		)
		(property "Value" "0R2J-2-GP"
			(at 0.064008 -3.993896 180)
			(unlocked yes)
			(layer "F.Fab")
			(hide yes)
			(effects
				(font
					(size 1.016 1.016)
					(thickness 0.1524)
				)
			)
		)
		(property "Device Type" "R402H16"
			(at 0.064008 -5.517896 180)
			(unlocked yes)
			(layer "F.Fab")
			(hide yes)
			(effects
				(font
					(size 1.016 1.016)
					(thickness 0.1524)
				)
			)
		)
		(duplicate_pad_numbers_are_jumpers no)
		(fp_line
			(start 0.508 -0.9398)
			(end -0.508 -0.9398)
			(stroke
				(width 0.1524)
				(type default)
			)
			(layer "F.SilkS")
		)
		(fp_line
			(start -0.508 -0.9398)
			(end -0.508 0.9398)
			(stroke
				(width 0.1524)
				(type default)
			)
			(layer "F.SilkS")
		)
		(fp_rect
			(start -0.508 0.9398)
			(end 0.508 -0.9398)
			(stroke
				(width 0)
				(type default)
			)
			(fill no)
			(layer "F.CrtYd")
		)
		(fp_rect
			(start -0.508 0.9398)
			(end 0.508 -0.9398)
			(stroke
				(width 0)
				(type default)
			)
			(fill no)
			(layer "F.Fab")
		)
		(pad "1" smd custom
			(at 0 -0.4445 180)
			(size 0.1397 0.1397)
			(layers "F.Cu" "F.Mask" "F.Paste")
			(net "SAS_FAULT_LED15")
			(options
				(clearance outline)
				(anchor circle)
			)
			(primitives
				(gr_poly
					(pts
						(arc
							(start -0.1778 -0.2794)
							(mid -0.249642 -0.249642)
							(end -0.2794 -0.1778)
						)
						(arc
							(start -0.2794 0.1778)
							(mid -0.249642 0.249642)
							(end -0.1778 0.2794)
						)
						(arc
							(start 0.1778 0.2794)
							(mid 0.249642 0.249642)
							(end 0.2794 0.1778)
						)
						(arc
							(start 0.2794 -0.1778)
							(mid 0.249642 -0.249642)
							(end 0.1778 -0.2794)
						)
					)
					(width 0)
					(fill yes)
				)
			)
		)
		(pad "2" smd custom
			(at 0 0.4445 180)
			(size 0.1397 0.1397)
			(layers "F.Cu" "F.Mask" "F.Paste")
			(net "SAS_HDD_LED_15")
			(options
				(clearance outline)
				(anchor circle)
			)
			(primitives
				(gr_poly
					(pts
						(arc
							(start -0.1778 -0.2794)
							(mid -0.249642 -0.249642)
							(end -0.2794 -0.1778)
						)
						(arc
							(start -0.2794 0.1778)
							(mid -0.249642 0.249642)
							(end -0.1778 0.2794)
						)
						(arc
							(start 0.1778 0.2794)
							(mid 0.249642 0.249642)
							(end 0.2794 0.1778)
						)
						(arc
							(start 0.2794 -0.1778)
							(mid 0.249642 -0.249642)
							(end 0.1778 -0.2794)
						)
					)
					(width 0)
					(fill yes)
				)
			)
		)
	)
)
